FILE_TYPE=LIBRARY_PARTS;
primitive 'DIODE_BIDIRECTIONAL';
  pin
    'A':
      PIN_NUMBER='(A)';
      BIDIRECTIONAL='TRUE';
      INPUT_LOAD='(-0.01,0.01)';
      OUTPUT_LOAD='(1.0,-1.0)';
    'C':
      PIN_NUMBER='(C)';
      BIDIRECTIONAL='TRUE';
      INPUT_LOAD='(-0.01,0.01)';
      OUTPUT_LOAD='(1.0,-1.0)';
  end_pin;
  body
    PART_NAME='DIODE_BIDIRECTIONAL';
    BODY_NAME='DIODE_BIDIRECTIONAL';
    PHYS_DES_PREFIX='D';
    CLASS='DISCRETE';
  end_body;
end_primitive;

END.
